# T6G (Grand Teton) — schematic netlist excerpt (pin names and nets, part order shuffled) for the footprints in the layout excerpt that follows; sources: Cadence DE-HDL packaged netlist, KiCad conversion of 04192023_DAF0TMB3IC0_F0TG_MB_C_brd_V02_OCP.brd

R919  Q_RES  4.7K 5% CHIP  pkg 0201LF  page 353 : A = TEST0_RT_CPU1_P3 ; B = GND
R6767  Q_RES  1K 1% CHIP  pkg 0201LF  page 184 : A = P1V8_CPU0_RT_1D ; B = SMB_RT_CPU0_P3_R_SCL
C6554  Q_CAP_DIFFBUS  DIFF BUS_0.22UF 6.3V 20% X6S  pkg C0201  page 286 : \1\ = P5E_CPU0_P1_TX_BUF_C_DN<10> ; \2\ = P5E_CPU0_P1_TX_BUF_DN<10>
R1285  Q_RES  4.7K 5% CHIP  pkg 0402LF  page 83 : A = FM_P1_PCC0_N ; B = PVDD18_S5_P1

(kicad_pcb
	(version 20260206)
	(generator "pcbnew")
	(generator_version "10.0")
	(general
		(thickness 1.6)
		(legacy_teardrops no)
	)
	(paper "A4")
	(title_block
		(title "04192023_DAF0TMB3IC0_F0TG_MB_C_brd_V02_OCP.brd")
		(comment 1 "Grand Teton / footprints 5767-5770 of 8354")
	)
	(layers
		(0 "F.Cu" signal "TOP")
		(4 "In1.Cu" signal "GND")
		(6 "In2.Cu" signal "IN1")
		(8 "In3.Cu" signal "GND1")
		(10 "In4.Cu" signal "IN2")
		(12 "In5.Cu" signal "GND2")
		(14 "In6.Cu" signal "IN3")
		(16 "In7.Cu" signal "GND3")
		(18 "In8.Cu" signal "VCC")
		(20 "In9.Cu" signal "VCC1")
		(22 "In10.Cu" signal "GND4")
		(24 "In11.Cu" signal "IN4")
		(26 "In12.Cu" signal "GND5")
		(28 "In13.Cu" signal "IN5")
		(30 "In14.Cu" signal "GND6")
		(32 "In15.Cu" signal "IN6")
		(34 "In16.Cu" signal "GND7")
		(2 "B.Cu" signal "BOTTOM")
		(9 "F.Adhes" user "F.Adhesive")
		(11 "B.Adhes" user "B.Adhesive")
		(13 "F.Paste" user "Package Geometry/Pastemask Top")
		(15 "B.Paste" user "Package Geometry/Pastemask Bottom")
		(5 "F.SilkS" user "Ref Des/Silkscreen Top")
		(7 "B.SilkS" user "Ref Des/Silkscreen Bottom")
		(1 "F.Mask" user "Board Geometry/Soldermask Top")
		(3 "B.Mask" user "Board Geometry/Soldermask Bottom")
		(17 "Dwgs.User" user "User.Drawings")
		(19 "Cmts.User" user "User.Comments")
		(21 "Eco1.User" user "User.Eco1")
		(23 "Eco2.User" user "User.Eco2")
		(25 "Edge.Cuts" user "Board Geometry/Outline")
		(27 "Margin" user)
		(31 "F.CrtYd" user "Package Geometry/Place Bound Top")
		(29 "B.CrtYd" user "Package Geometry/Place Bound Bottom")
		(35 "F.Fab" user "Ref Des/Assembly Top")
		(33 "B.Fab" user "Ref Des/Assembly Bottom")
	)
	(footprint ""
		(layer "B.Cu")
		(at 110.365794 -385.58216 180)
		(property "Reference" "R919"
			(at 0 0 0)
			(layer "B.SilkS")
			(hide yes)
			(effects
				(font
					(size 1.27 1.27)
				)
				(justify mirror)
			)
		)
		(property "Value" ""
			(at 0 0 0)
			(layer "B.Fab")
			(effects
				(font
					(size 1.27 1.27)
				)
				(justify mirror)
			)
		)
		(duplicate_pad_numbers_are_jumpers no)
		(fp_line
			(start 0.32512 0.175006)
			(end 0.32512 -0.175006)
			(stroke
				(width 0.1)
				(type default)
			)
			(layer "B.Fab")
		)
		(fp_line
			(start 0.32512 -0.175006)
			(end -0.32512 -0.175006)
			(stroke
				(width 0.1)
				(type default)
			)
			(layer "B.Fab")
		)
		(fp_line
			(start -0.32512 0.175006)
			(end 0.32512 0.175006)
			(stroke
				(width 0.1)
				(type default)
			)
			(layer "B.Fab")
		)
		(fp_line
			(start -0.32512 -0.175006)
			(end -0.32512 0.175006)
			(stroke
				(width 0.1)
				(type default)
			)
			(layer "B.Fab")
		)
		(pad "1" smd rect
			(at 0.2667 0)
			(size 0.3048 0.381)
			(layers "B.Cu" "B.Mask" "B.Paste")
			(net "TEST0_RT_CPU1_P3")
		)
		(pad "2" smd rect
			(at -0.2667 0 180)
			(size 0.3048 0.381)
			(layers "B.Cu" "B.Mask" "B.Paste")
			(net "GND")
		)
	)
	(footprint ""
		(layer "B.Cu")
		(at 231.648 -336.169 -90)
		(property "Reference" "R6767"
			(at 0 0 90)
			(layer "B.SilkS")
			(hide yes)
			(effects
				(font
					(size 1.27 1.27)
				)
				(justify mirror)
			)
		)
		(property "Value" ""
			(at 0 0 90)
			(layer "B.Fab")
			(effects
				(font
					(size 1.27 1.27)
				)
				(justify mirror)
			)
		)
		(duplicate_pad_numbers_are_jumpers no)
		(fp_line
			(start -0.32512 0.175006)
			(end 0.32512 0.175006)
			(stroke
				(width 0.1)
				(type default)
			)
			(layer "B.Fab")
		)
		(fp_line
			(start 0.32512 0.175006)
			(end 0.32512 -0.175006)
			(stroke
				(width 0.1)
				(type default)
			)
			(layer "B.Fab")
		)
		(fp_line
			(start -0.32512 -0.175006)
			(end -0.32512 0.175006)
			(stroke
				(width 0.1)
				(type default)
			)
			(layer "B.Fab")
		)
		(fp_line
			(start 0.32512 -0.175006)
			(end -0.32512 -0.175006)
			(stroke
				(width 0.1)
				(type default)
			)
			(layer "B.Fab")
		)
		(pad "1" smd rect
			(at 0.2667 0 90)
			(size 0.3048 0.381)
			(layers "B.Cu" "B.Mask" "B.Paste")
			(net "P1V8_CPU0_RT_1D")
		)
		(pad "2" smd rect
			(at -0.2667 0 270)
			(size 0.3048 0.381)
			(layers "B.Cu" "B.Mask" "B.Paste")
			(net "SMB_RT_CPU0_P3_R_SCL")
		)
	)
	(footprint ""
		(layer "B.Cu")
		(at 181.57063 -133.838696 -90)
		(property "Reference" "R1285"
			(at 0 0 90)
			(layer "B.SilkS")
			(hide yes)
			(effects
				(font
					(size 1.27 1.27)
				)
				(justify mirror)
			)
		)
		(property "Value" ""
			(at 0 0 90)
			(layer "B.Fab")
			(effects
				(font
					(size 1.27 1.27)
				)
				(justify mirror)
			)
		)
		(duplicate_pad_numbers_are_jumpers no)
		(fp_line
			(start -0.7874 0.4064)
			(end 0.7874 0.4064)
			(stroke
				(width 0.1524)
				(type default)
			)
			(layer "B.SilkS")
		)
		(fp_line
			(start 0.7874 0.4064)
			(end 0.7874 -0.4064)
			(stroke
				(width 0.1524)
				(type default)
			)
			(layer "B.SilkS")
		)
		(fp_line
			(start -0.7874 -0.4064)
			(end -0.7874 0.4064)
			(stroke
				(width 0.1524)
				(type default)
			)
			(layer "B.SilkS")
		)
		(fp_line
			(start 0.7874 -0.4064)
			(end -0.7874 -0.4064)
			(stroke
				(width 0.1524)
				(type default)
			)
			(layer "B.SilkS")
		)
		(fp_line
			(start -0.67945 0.3048)
			(end -0.120396 0.3048)
			(stroke
				(width 0.1)
				(type default)
			)
			(layer "B.Fab")
		)
		(fp_line
			(start -0.120396 0.3048)
			(end -0.120396 0.2794)
			(stroke
				(width 0.1)
				(type default)
			)
			(layer "B.Fab")
		)
		(fp_line
			(start 0.12065 0.3048)
			(end 0.67945 0.3048)
			(stroke
				(width 0.1)
				(type default)
			)
			(layer "B.Fab")
		)
		(fp_line
			(start 0.67945 0.3048)
			(end 0.67945 -0.305054)
			(stroke
				(width 0.1)
				(type default)
			)
			(layer "B.Fab")
		)
		(fp_line
			(start -0.120396 0.2794)
			(end 0.12065 0.2794)
			(stroke
				(width 0.1)
				(type default)
			)
			(layer "B.Fab")
		)
		(fp_line
			(start 0.12065 0.2794)
			(end 0.12065 0.3048)
			(stroke
				(width 0.1)
				(type default)
			)
			(layer "B.Fab")
		)
		(fp_line
			(start -0.12065 -0.2794)
			(end -0.12065 -0.3048)
			(stroke
				(width 0.1)
				(type default)
			)
			(layer "B.Fab")
		)
		(fp_line
			(start 0.12065 -0.2794)
			(end -0.12065 -0.2794)
			(stroke
				(width 0.1)
				(type default)
			)
			(layer "B.Fab")
		)
		(fp_line
			(start -0.67945 -0.3048)
			(end -0.67945 0.3048)
			(stroke
				(width 0.1)
				(type default)
			)
			(layer "B.Fab")
		)
		(fp_line
			(start -0.12065 -0.3048)
			(end -0.67945 -0.3048)
			(stroke
				(width 0.1)
				(type default)
			)
			(layer "B.Fab")
		)
		(fp_line
			(start 0.12065 -0.305054)
			(end 0.12065 -0.2794)
			(stroke
				(width 0.1)
				(type default)
			)
			(layer "B.Fab")
		)
		(fp_line
			(start 0.67945 -0.305054)
			(end 0.12065 -0.305054)
			(stroke
				(width 0.1)
				(type default)
			)
			(layer "B.Fab")
		)
		(pad "1" smd circle
			(at 0.40005 0 90)
			(size 0 0)
			(layers "B.Cu" "B.Mask" "B.Paste")
			(net "FM_P1_PCC0_N")
		)
		(pad "2" smd circle
			(at -0.40005 0 90)
			(size 0 0)
			(layers "B.Cu" "B.Mask" "B.Paste")
			(net "PVDD18_S5_P1")
		)
	)
	(footprint ""
		(layer "B.Cu")
		(at 335.932526 -416.899344 90)
		(property "Reference" "C6554"
			(at 0 0 90)
			(layer "B.SilkS")
			(hide yes)
			(effects
				(font
					(size 1.27 1.27)
				)
				(justify mirror)
			)
		)
		(property "Value" ""
			(at 0 0 90)
			(layer "B.Fab")
			(effects
				(font
					(size 1.27 1.27)
				)
				(justify mirror)
			)
		)
		(duplicate_pad_numbers_are_jumpers no)
		(fp_line
			(start 0.299974 -0.150114)
			(end -0.299974 -0.150114)
			(stroke
				(width 0.1)
				(type default)
			)
			(layer "B.Fab")
		)
		(fp_line
			(start -0.299974 -0.150114)
			(end -0.299974 0.150114)
			(stroke
				(width 0.1)
				(type default)
			)
			(layer "B.Fab")
		)
		(fp_line
			(start 0.299974 0.150114)
			(end 0.299974 -0.150114)
			(stroke
				(width 0.1)
				(type default)
			)
			(layer "B.Fab")
		)
		(fp_line
			(start -0.299974 0.150114)
			(end 0.299974 0.150114)
			(stroke
				(width 0.1)
				(type default)
			)
			(layer "B.Fab")
		)
		(pad "1" smd rect
			(at 0.2667 0 270)
			(size 0.3048 0.381)
			(layers "B.Cu" "B.Mask" "B.Paste")
			(net "P5E_CPU0_P1_TX_BUF_C_DN<10>")
		)
		(pad "2" smd rect
			(at -0.2667 0 270)
			(size 0.3048 0.381)
			(layers "B.Cu" "B.Mask" "B.Paste")
			(net "P5E_CPU0_P1_TX_BUF_DN<10>")
		)
	)
)
